# S9S_MB_2U (Grand Teton) — schematic netlist excerpt (pin names and nets, part order shuffled) for the footprints in the layout excerpt that follows; sources: Cadence DE-HDL packaged netlist, KiCad conversion of 03242023_DA0F0TMBIJ0_F0T_Motherboard_J_brd_V01_OCP.brd

R2727  Q_RES  33.2 1% CHIP  pkg 0402LF  page 114 : A = PWRGD_CHA_CPU0_DIMM2 ; B = PWRGD_FAIL_CPU0_AB
PC448_P1_1  Q_CAP  22UF 16V 20% X6S  pkg C0805  page 293 : A = SW_P12V_PVCCINFAON_CPU1_FLT ; B = GND
R79  Q_RES  10K 1% CHIP  pkg 0402LF  page 106 : A = PD_CHE_CPU1_DIMM1_SAA ; B = GND

(kicad_pcb
	(version 20260206)
	(generator "pcbnew")
	(generator_version "10.0")
	(general
		(thickness 1.6)
		(legacy_teardrops no)
	)
	(paper "A4")
	(title_block
		(title "03242023_DA0F0TMBIJ0_F0T_Motherboard_J_brd_V01_OCP.brd")
		(comment 1 "Grand Teton / footprints 4640-4642 of 6105")
	)
	(layers
		(0 "F.Cu" signal "TOP")
		(4 "In1.Cu" signal "GND")
		(6 "In2.Cu" signal "IN1")
		(8 "In3.Cu" signal "GND1")
		(10 "In4.Cu" signal "IN2")
		(12 "In5.Cu" signal "GND2")
		(14 "In6.Cu" signal "IN3")
		(16 "In7.Cu" signal "GND3")
		(18 "In8.Cu" signal "VCC")
		(20 "In9.Cu" signal "VCC1")
		(22 "In10.Cu" signal "GND4")
		(24 "In11.Cu" signal "IN4")
		(26 "In12.Cu" signal "GND5")
		(28 "In13.Cu" signal "IN5")
		(30 "In14.Cu" signal "GND6")
		(32 "In15.Cu" signal "IN6")
		(34 "In16.Cu" signal "GND7")
		(2 "B.Cu" signal "BOTTOM")
		(9 "F.Adhes" user "F.Adhesive")
		(11 "B.Adhes" user "B.Adhesive")
		(13 "F.Paste" user "Package Geometry/Pastemask Top")
		(15 "B.Paste" user "Package Geometry/Pastemask Bottom")
		(5 "F.SilkS" user "Ref Des/Silkscreen Top")
		(7 "B.SilkS" user "Ref Des/Silkscreen Bottom")
		(1 "F.Mask" user "Board Geometry/Soldermask Top")
		(3 "B.Mask" user "Board Geometry/Soldermask Bottom")
		(17 "Dwgs.User" user "User.Drawings")
		(19 "Cmts.User" user "User.Comments")
		(21 "Eco1.User" user "User.Eco1")
		(23 "Eco2.User" user "User.Eco2")
		(25 "Edge.Cuts" user "Board Geometry/Outline")
		(27 "Margin" user)
		(31 "F.CrtYd" user "Package Geometry/Place Bound Top")
		(29 "B.CrtYd" user "Package Geometry/Place Bound Bottom")
		(35 "F.Fab" user "Ref Des/Assembly Top")
		(33 "B.Fab" user "Ref Des/Assembly Bottom")
	)
	(footprint ""
		(layer "B.Cu")
		(at 54.880002 -159.734758 180)
		(property "Reference" "PC448_P1_1"
			(at 0 0 0)
			(layer "B.SilkS")
			(hide yes)
			(effects
				(font
					(size 1.27 1.27)
				)
				(justify mirror)
			)
		)
		(property "Value" ""
			(at 0 0 0)
			(layer "B.Fab")
			(effects
				(font
					(size 1.27 1.27)
				)
				(justify mirror)
			)
		)
		(duplicate_pad_numbers_are_jumpers no)
		(fp_line
			(start 1.524 0.762)
			(end 1.524 -0.762)
			(stroke
				(width 0.1524)
				(type default)
			)
			(layer "B.SilkS")
		)
		(fp_line
			(start 1.524 -0.762)
			(end -1.524 -0.762)
			(stroke
				(width 0.1524)
				(type default)
			)
			(layer "B.SilkS")
		)
		(fp_line
			(start -1.524 0.762)
			(end 1.524 0.762)
			(stroke
				(width 0.1524)
				(type default)
			)
			(layer "B.SilkS")
		)
		(fp_line
			(start -1.524 -0.762)
			(end -1.524 0.762)
			(stroke
				(width 0.1524)
				(type default)
			)
			(layer "B.SilkS")
		)
		(fp_line
			(start 1.1049 0.724916)
			(end -1.1049 0.724916)
			(stroke
				(width 0.1)
				(type default)
			)
			(layer "B.Fab")
		)
		(fp_line
			(start 1.1049 -0.724916)
			(end 1.1049 0.724916)
			(stroke
				(width 0.1)
				(type default)
			)
			(layer "B.Fab")
		)
		(fp_line
			(start -1.1049 0.724916)
			(end -1.1049 -0.724916)
			(stroke
				(width 0.1)
				(type default)
			)
			(layer "B.Fab")
		)
		(fp_line
			(start -1.1049 -0.724916)
			(end 1.1049 -0.724916)
			(stroke
				(width 0.1)
				(type default)
			)
			(layer "B.Fab")
		)
		(pad "1" smd rect
			(at 0.889 0 180)
			(size 1.016 1.27)
			(layers "B.Cu" "B.Mask" "B.Paste")
			(net "SW_P12V_PVCCINFAON_CPU1_FLT")
		)
		(pad "2" smd rect
			(at -0.889 0 180)
			(size 1.016 1.27)
			(layers "B.Cu" "B.Mask" "B.Paste")
			(net "GND")
		)
	)
	(footprint ""
		(layer "B.Cu")
		(at 312.592974 -319.069212 90)
		(property "Reference" "R2727"
			(at 0 0 90)
			(layer "B.SilkS")
			(hide yes)
			(effects
				(font
					(size 1.27 1.27)
				)
				(justify mirror)
			)
		)
		(property "Value" ""
			(at 0 0 90)
			(layer "B.Fab")
			(effects
				(font
					(size 1.27 1.27)
				)
				(justify mirror)
			)
		)
		(duplicate_pad_numbers_are_jumpers no)
		(fp_line
			(start 0.7874 -0.4064)
			(end -0.7874 -0.4064)
			(stroke
				(width 0.1524)
				(type default)
			)
			(layer "B.SilkS")
		)
		(fp_line
			(start -0.7874 -0.4064)
			(end -0.7874 0.4064)
			(stroke
				(width 0.1524)
				(type default)
			)
			(layer "B.SilkS")
		)
		(fp_line
			(start 0.7874 0.4064)
			(end 0.7874 -0.4064)
			(stroke
				(width 0.1524)
				(type default)
			)
			(layer "B.SilkS")
		)
		(fp_line
			(start -0.7874 0.4064)
			(end 0.7874 0.4064)
			(stroke
				(width 0.1524)
				(type default)
			)
			(layer "B.SilkS")
		)
		(fp_line
			(start 0.67945 -0.305054)
			(end 0.12065 -0.305054)
			(stroke
				(width 0.1)
				(type default)
			)
			(layer "B.Fab")
		)
		(fp_line
			(start 0.12065 -0.305054)
			(end 0.12065 -0.2794)
			(stroke
				(width 0.1)
				(type default)
			)
			(layer "B.Fab")
		)
		(fp_line
			(start -0.12065 -0.3048)
			(end -0.67945 -0.3048)
			(stroke
				(width 0.1)
				(type default)
			)
			(layer "B.Fab")
		)
		(fp_line
			(start -0.67945 -0.3048)
			(end -0.67945 0.3048)
			(stroke
				(width 0.1)
				(type default)
			)
			(layer "B.Fab")
		)
		(fp_line
			(start 0.12065 -0.2794)
			(end -0.12065 -0.2794)
			(stroke
				(width 0.1)
				(type default)
			)
			(layer "B.Fab")
		)
		(fp_line
			(start -0.12065 -0.2794)
			(end -0.12065 -0.3048)
			(stroke
				(width 0.1)
				(type default)
			)
			(layer "B.Fab")
		)
		(fp_line
			(start 0.12065 0.2794)
			(end 0.12065 0.3048)
			(stroke
				(width 0.1)
				(type default)
			)
			(layer "B.Fab")
		)
		(fp_line
			(start -0.120396 0.2794)
			(end 0.12065 0.2794)
			(stroke
				(width 0.1)
				(type default)
			)
			(layer "B.Fab")
		)
		(fp_line
			(start 0.67945 0.3048)
			(end 0.67945 -0.305054)
			(stroke
				(width 0.1)
				(type default)
			)
			(layer "B.Fab")
		)
		(fp_line
			(start 0.12065 0.3048)
			(end 0.67945 0.3048)
			(stroke
				(width 0.1)
				(type default)
			)
			(layer "B.Fab")
		)
		(fp_line
			(start -0.120396 0.3048)
			(end -0.120396 0.2794)
			(stroke
				(width 0.1)
				(type default)
			)
			(layer "B.Fab")
		)
		(fp_line
			(start -0.67945 0.3048)
			(end -0.120396 0.3048)
			(stroke
				(width 0.1)
				(type default)
			)
			(layer "B.Fab")
		)
		(pad "1" smd circle
			(at 0.40005 0 270)
			(size 0 0)
			(layers "B.Cu" "B.Mask" "B.Paste")
			(net "PWRGD_CHA_CPU0_DIMM2")
		)
		(pad "2" smd circle
			(at -0.40005 0 270)
			(size 0 0)
			(layers "B.Cu" "B.Mask" "B.Paste")
			(net "PWRGD_FAIL_CPU0_AB")
		)
	)
	(footprint ""
		(layer "B.Cu")
		(at 170.78579 -319.006728 180)
		(property "Reference" "R79"
			(at 0 0 0)
			(layer "B.SilkS")
			(hide yes)
			(effects
				(font
					(size 1.27 1.27)
				)
				(justify mirror)
			)
		)
		(property "Value" ""
			(at 0 0 0)
			(layer "B.Fab")
			(effects
				(font
					(size 1.27 1.27)
				)
				(justify mirror)
			)
		)
		(duplicate_pad_numbers_are_jumpers no)
		(fp_line
			(start 0.7874 0.4064)
			(end 0.7874 -0.4064)
			(stroke
				(width 0.1524)
				(type default)
			)
			(layer "B.SilkS")
		)
		(fp_line
			(start 0.7874 -0.4064)
			(end -0.7874 -0.4064)
			(stroke
				(width 0.1524)
				(type default)
			)
			(layer "B.SilkS")
		)
		(fp_line
			(start -0.7874 0.4064)
			(end 0.7874 0.4064)
			(stroke
				(width 0.1524)
				(type default)
			)
			(layer "B.SilkS")
		)
		(fp_line
			(start -0.7874 -0.4064)
			(end -0.7874 0.4064)
			(stroke
				(width 0.1524)
				(type default)
			)
			(layer "B.SilkS")
		)
		(fp_line
			(start 0.67945 0.3048)
			(end 0.67945 -0.305054)
			(stroke
				(width 0.1)
				(type default)
			)
			(layer "B.Fab")
		)
		(fp_line
			(start 0.67945 -0.305054)
			(end 0.12065 -0.305054)
			(stroke
				(width 0.1)
				(type default)
			)
			(layer "B.Fab")
		)
		(fp_line
			(start 0.12065 0.3048)
			(end 0.67945 0.3048)
			(stroke
				(width 0.1)
				(type default)
			)
			(layer "B.Fab")
		)
		(fp_line
			(start 0.12065 0.2794)
			(end 0.12065 0.3048)
			(stroke
				(width 0.1)
				(type default)
			)
			(layer "B.Fab")
		)
		(fp_line
			(start 0.12065 -0.2794)
			(end -0.12065 -0.2794)
			(stroke
				(width 0.1)
				(type default)
			)
			(layer "B.Fab")
		)
		(fp_line
			(start 0.12065 -0.305054)
			(end 0.12065 -0.2794)
			(stroke
				(width 0.1)
				(type default)
			)
			(layer "B.Fab")
		)
		(fp_line
			(start -0.120396 0.3048)
			(end -0.120396 0.2794)
			(stroke
				(width 0.1)
				(type default)
			)
			(layer "B.Fab")
		)
		(fp_line
			(start -0.120396 0.2794)
			(end 0.12065 0.2794)
			(stroke
				(width 0.1)
				(type default)
			)
			(layer "B.Fab")
		)
		(fp_line
			(start -0.12065 -0.2794)
			(end -0.12065 -0.3048)
			(stroke
				(width 0.1)
				(type default)
			)
			(layer "B.Fab")
		)
		(fp_line
			(start -0.12065 -0.3048)
			(end -0.67945 -0.3048)
			(stroke
				(width 0.1)
				(type default)
			)
			(layer "B.Fab")
		)
		(fp_line
			(start -0.67945 0.3048)
			(end -0.120396 0.3048)
			(stroke
				(width 0.1)
				(type default)
			)
			(layer "B.Fab")
		)
		(fp_line
			(start -0.67945 -0.3048)
			(end -0.67945 0.3048)
			(stroke
				(width 0.1)
				(type default)
			)
			(layer "B.Fab")
		)
		(pad "1" smd circle
			(at 0.40005 0)
			(size 0 0)
			(layers "B.Cu" "B.Mask" "B.Paste")
			(net "PD_CHE_CPU1_DIMM1_SAA")
		)
		(pad "2" smd circle
			(at -0.40005 0)
			(size 0 0)
			(layers "B.Cu" "B.Mask" "B.Paste")
			(net "GND")
		)
	)
)
